# S9S_MB_2U (Grand Teton) — schematic netlist excerpt (pin names and nets, part order shuffled) for the footprints in the layout excerpt that follows; sources: Cadence DE-HDL packaged netlist, KiCad conversion of 03242023_DA0F0TMBIJ0_F0T_Motherboard_J_brd_V01_OCP.brd

PR5481  Q_RES  4.53K 1% CHIP  pkg 0402LF  page 156 : A = P3V3_OCP_SENSE_1 ; B = GND
R3512  Q_RES  100K 1% EMPTY  pkg 0402LF  page 148 : A = P3V3_AUX ; B = FM_GPU_PWRGD

(kicad_pcb
	(version 20260206)
	(generator "pcbnew")
	(generator_version "10.0")
	(general
		(thickness 1.6)
		(legacy_teardrops no)
	)
	(paper "A4")
	(title_block
		(title "03242023_DA0F0TMBIJ0_F0T_Motherboard_J_brd_V01_OCP.brd")
		(comment 1 "Grand Teton / footprints 2983-2984 of 6105")
	)
	(layers
		(0 "F.Cu" signal "TOP")
		(4 "In1.Cu" signal "GND")
		(6 "In2.Cu" signal "IN1")
		(8 "In3.Cu" signal "GND1")
		(10 "In4.Cu" signal "IN2")
		(12 "In5.Cu" signal "GND2")
		(14 "In6.Cu" signal "IN3")
		(16 "In7.Cu" signal "GND3")
		(18 "In8.Cu" signal "VCC")
		(20 "In9.Cu" signal "VCC1")
		(22 "In10.Cu" signal "GND4")
		(24 "In11.Cu" signal "IN4")
		(26 "In12.Cu" signal "GND5")
		(28 "In13.Cu" signal "IN5")
		(30 "In14.Cu" signal "GND6")
		(32 "In15.Cu" signal "IN6")
		(34 "In16.Cu" signal "GND7")
		(2 "B.Cu" signal "BOTTOM")
		(9 "F.Adhes" user "F.Adhesive")
		(11 "B.Adhes" user "B.Adhesive")
		(13 "F.Paste" user "Package Geometry/Pastemask Top")
		(15 "B.Paste" user "Package Geometry/Pastemask Bottom")
		(5 "F.SilkS" user "Ref Des/Silkscreen Top")
		(7 "B.SilkS" user "Ref Des/Silkscreen Bottom")
		(1 "F.Mask" user "Board Geometry/Soldermask Top")
		(3 "B.Mask" user "Board Geometry/Soldermask Bottom")
		(17 "Dwgs.User" user "User.Drawings")
		(19 "Cmts.User" user "User.Comments")
		(21 "Eco1.User" user "User.Eco1")
		(23 "Eco2.User" user "User.Eco2")
		(25 "Edge.Cuts" user "Board Geometry/Outline")
		(27 "Margin" user)
		(31 "F.CrtYd" user "Package Geometry/Place Bound Top")
		(29 "B.CrtYd" user "Package Geometry/Place Bound Bottom")
		(35 "F.Fab" user "Ref Des/Assembly Top")
		(33 "B.Fab" user "Ref Des/Assembly Bottom")
	)
	(footprint ""
		(layer "F.Cu")
		(at 24.046942 -417.159948)
		(property "Reference" "R3512"
			(at 0 0 0)
			(layer "F.SilkS")
			(hide yes)
			(effects
				(font
					(size 1.27 1.27)
				)
			)
		)
		(property "Value" ""
			(at 0 0 0)
			(layer "F.Fab")
			(effects
				(font
					(size 1.27 1.27)
				)
			)
		)
		(duplicate_pad_numbers_are_jumpers no)
		(fp_line
			(start -0.7874 -0.4064)
			(end 0.7874 -0.4064)
			(stroke
				(width 0.1524)
				(type default)
			)
			(layer "F.SilkS")
		)
		(fp_line
			(start -0.7874 0.4064)
			(end -0.7874 -0.4064)
			(stroke
				(width 0.1524)
				(type default)
			)
			(layer "F.SilkS")
		)
		(fp_line
			(start 0.7874 -0.4064)
			(end 0.7874 0.4064)
			(stroke
				(width 0.1524)
				(type default)
			)
			(layer "F.SilkS")
		)
		(fp_line
			(start 0.7874 0.4064)
			(end -0.7874 0.4064)
			(stroke
				(width 0.1524)
				(type default)
			)
			(layer "F.SilkS")
		)
		(fp_line
			(start -0.67945 -0.305054)
			(end -0.12065 -0.305054)
			(stroke
				(width 0.1)
				(type default)
			)
			(layer "F.Fab")
		)
		(fp_line
			(start -0.67945 0.3048)
			(end -0.67945 -0.305054)
			(stroke
				(width 0.1)
				(type default)
			)
			(layer "F.Fab")
		)
		(fp_line
			(start -0.12065 -0.305054)
			(end -0.12065 -0.2794)
			(stroke
				(width 0.1)
				(type default)
			)
			(layer "F.Fab")
		)
		(fp_line
			(start -0.12065 -0.2794)
			(end 0.12065 -0.2794)
			(stroke
				(width 0.1)
				(type default)
			)
			(layer "F.Fab")
		)
		(fp_line
			(start -0.12065 0.2794)
			(end -0.12065 0.3048)
			(stroke
				(width 0.1)
				(type default)
			)
			(layer "F.Fab")
		)
		(fp_line
			(start -0.12065 0.3048)
			(end -0.67945 0.3048)
			(stroke
				(width 0.1)
				(type default)
			)
			(layer "F.Fab")
		)
		(fp_line
			(start 0.120396 0.2794)
			(end -0.12065 0.2794)
			(stroke
				(width 0.1)
				(type default)
			)
			(layer "F.Fab")
		)
		(fp_line
			(start 0.120396 0.3048)
			(end 0.120396 0.2794)
			(stroke
				(width 0.1)
				(type default)
			)
			(layer "F.Fab")
		)
		(fp_line
			(start 0.12065 -0.3048)
			(end 0.67945 -0.3048)
			(stroke
				(width 0.1)
				(type default)
			)
			(layer "F.Fab")
		)
		(fp_line
			(start 0.12065 -0.2794)
			(end 0.12065 -0.3048)
			(stroke
				(width 0.1)
				(type default)
			)
			(layer "F.Fab")
		)
		(fp_line
			(start 0.67945 -0.3048)
			(end 0.67945 0.3048)
			(stroke
				(width 0.1)
				(type default)
			)
			(layer "F.Fab")
		)
		(fp_line
			(start 0.67945 0.3048)
			(end 0.120396 0.3048)
			(stroke
				(width 0.1)
				(type default)
			)
			(layer "F.Fab")
		)
		(pad "1" smd circle
			(at -0.40005 0)
			(size 0 0)
			(layers "F.Cu" "F.Mask" "F.Paste")
			(net "P3V3_AUX")
		)
		(pad "2" smd circle
			(at 0.40005 0)
			(size 0 0)
			(layers "F.Cu" "F.Mask" "F.Paste")
			(net "FM_GPU_PWRGD")
		)
	)
	(footprint ""
		(layer "F.Cu")
		(at 432.974496 -109.13745 90)
		(property "Reference" "PR5481"
			(at 0 0 90)
			(layer "F.SilkS")
			(hide yes)
			(effects
				(font
					(size 1.27 1.27)
				)
			)
		)
		(property "Value" ""
			(at 0 0 90)
			(layer "F.Fab")
			(effects
				(font
					(size 1.27 1.27)
				)
			)
		)
		(duplicate_pad_numbers_are_jumpers no)
		(fp_line
			(start 0.7874 -0.4064)
			(end 0.7874 0.4064)
			(stroke
				(width 0.1524)
				(type default)
			)
			(layer "F.SilkS")
		)
		(fp_line
			(start -0.7874 -0.4064)
			(end 0.7874 -0.4064)
			(stroke
				(width 0.1524)
				(type default)
			)
			(layer "F.SilkS")
		)
		(fp_line
			(start 0.7874 0.4064)
			(end -0.7874 0.4064)
			(stroke
				(width 0.1524)
				(type default)
			)
			(layer "F.SilkS")
		)
		(fp_line
			(start -0.7874 0.4064)
			(end -0.7874 -0.4064)
			(stroke
				(width 0.1524)
				(type default)
			)
			(layer "F.SilkS")
		)
		(fp_line
			(start -0.12065 -0.305054)
			(end -0.12065 -0.2794)
			(stroke
				(width 0.1)
				(type default)
			)
			(layer "F.Fab")
		)
		(fp_line
			(start -0.67945 -0.305054)
			(end -0.12065 -0.305054)
			(stroke
				(width 0.1)
				(type default)
			)
			(layer "F.Fab")
		)
		(fp_line
			(start 0.67945 -0.3048)
			(end 0.67945 0.3048)
			(stroke
				(width 0.1)
				(type default)
			)
			(layer "F.Fab")
		)
		(fp_line
			(start 0.12065 -0.3048)
			(end 0.67945 -0.3048)
			(stroke
				(width 0.1)
				(type default)
			)
			(layer "F.Fab")
		)
		(fp_line
			(start 0.12065 -0.2794)
			(end 0.12065 -0.3048)
			(stroke
				(width 0.1)
				(type default)
			)
			(layer "F.Fab")
		)
		(fp_line
			(start -0.12065 -0.2794)
			(end 0.12065 -0.2794)
			(stroke
				(width 0.1)
				(type default)
			)
			(layer "F.Fab")
		)
		(fp_line
			(start 0.120396 0.2794)
			(end -0.12065 0.2794)
			(stroke
				(width 0.1)
				(type default)
			)
			(layer "F.Fab")
		)
		(fp_line
			(start -0.12065 0.2794)
			(end -0.12065 0.3048)
			(stroke
				(width 0.1)
				(type default)
			)
			(layer "F.Fab")
		)
		(fp_line
			(start 0.67945 0.3048)
			(end 0.120396 0.3048)
			(stroke
				(width 0.1)
				(type default)
			)
			(layer "F.Fab")
		)
		(fp_line
			(start 0.120396 0.3048)
			(end 0.120396 0.2794)
			(stroke
				(width 0.1)
				(type default)
			)
			(layer "F.Fab")
		)
		(fp_line
			(start -0.12065 0.3048)
			(end -0.67945 0.3048)
			(stroke
				(width 0.1)
				(type default)
			)
			(layer "F.Fab")
		)
		(fp_line
			(start -0.67945 0.3048)
			(end -0.67945 -0.305054)
			(stroke
				(width 0.1)
				(type default)
			)
			(layer "F.Fab")
		)
		(pad "1" smd circle
			(at -0.40005 0 90)
			(size 0 0)
			(layers "F.Cu" "F.Mask" "F.Paste")
			(net "P3V3_OCP_SENSE_1")
		)
		(pad "2" smd circle
			(at 0.40005 0 90)
			(size 0 0)
			(layers "F.Cu" "F.Mask" "F.Paste")
			(net "GND")
		)
	)
)
